# S9S_MB_2U (Grand Teton) — schematic netlist excerpt (pin names and nets, part order shuffled) for the footprints in the layout excerpt that follows; sources: Cadence DE-HDL packaged netlist, KiCad conversion of 03242023_DA0F0TMBIJ0_F0T_Motherboard_J_brd_V01_OCP.brd

J27  SCONN288_ADR50017P130CC  SCONN288_ADR50017-P130CC IO  pkg DDR288S_1-1VXB  page 108
  VIN_BULK0  = P12V_S3_AUX_CPU1_NVDIMM
  RFU0  = TP_CHF_CPU1_DIMM1_FRU_0
  VIN_MGMT  = P3V3_AUX
  HSCL  = I3C_SPD_DDREFGH_CPU1_LVC1_SCL_2
  HSDA  = I3C_SPD_DDREFGH_CPU1_LVC1_SDA
  VSS0  = GND
  DQ0_A  = M_F_CPU1_SA_DQ<0>
  VSS1  = GND
  DQ1_A  = M_F_CPU1_SA_DQ<1>
  VSS2  = GND
  DQS0_A_T  = M_F_CPU1_SA_DQS_DP<0>
  DQS0_A_C  = M_F_CPU1_SA_DQS_DN<0>
  VSS3  = GND
  DQ4_A  = M_F_CPU1_SA_DQ<4>
  VSS4  = GND
  DQ5_A  = M_F_CPU1_SA_DQ<5>
  VSS5  = GND
  DQ8_A  = M_F_CPU1_SA_DQ<8>
  VSS6  = GND
  DQ9_A  = M_F_CPU1_SA_DQ<9>
  VSS7  = GND
  DQS1_A_T  = M_F_CPU1_SA_DQS_DP<1>
  DQS1_A_C  = M_F_CPU1_SA_DQS_DN<1>
  VSS8  = GND
  DQ12_A  = M_F_CPU1_SA_DQ<12>
  VSS9  = GND
  DQ13_A  = M_F_CPU1_SA_DQ<13>
  VSS10  = GND
  DQ16_A  = M_F_CPU1_SA_DQ<16>
  VSS11  = GND
  DQ17_A  = M_F_CPU1_SA_DQ<17>
  VSS12  = GND
  DQS2_A_T  = M_F_CPU1_SA_DQS_DP<2>
  DQS2_A_C  = M_F_CPU1_SA_DQS_DN<2>
  VSS13  = GND
  DQ20_A  = M_F_CPU1_SA_DQ<20>
  VSS14  = GND
  DQ21_A  = M_F_CPU1_SA_DQ<21>
  VSS15  = GND
  DQ24_A  = M_F_CPU1_SA_DQ<24>
  VSS16  = GND
  DQ25_A  = M_F_CPU1_SA_DQ<25>
  VSS17  = GND
  DQS3_A_T  = M_F_CPU1_SA_DQS_DP<3>
  DQS3_A_C  = M_F_CPU1_SA_DQS_DN<3>
  VSS18  = GND
  DQ28_A  = M_F_CPU1_SA_DQ<28>
  VSS19  = GND
  DQ29_A  = M_F_CPU1_SA_DQ<29>
  VSS20  = GND
  CB0_A  = M_F_CPU1_SA_CB<0>
  VSS21  = GND
  CB1_A  = M_F_CPU1_SA_CB<1>
  VSS22  = GND
  DQS4_A_T  = M_F_CPU1_SA_DQS_DP<4>
  DQS4_A_C  = M_F_CPU1_SA_DQS_DN<4>
  VSS23  = GND
  CB4_A  = M_F_CPU1_SA_CB<4>
  VSS24  = GND
  CB5_A  = M_F_CPU1_SA_CB<5>
  VSS25  = GND
  ALERT_N  = M_F_CPU1_ALERT_N
  VSS26  = GND
  CS0_A_N  = M_F_CPU1_SA_CS_N<0>
  VSS27  = GND
  CA0_A  = M_F_CPU1_SA_CA<0>
  VSS28  = GND
  CA2_A  = M_F_CPU1_SA_CA<2>
  VSS29  = GND
  CA4_A  = M_F_CPU1_SA_CA<4>
  VSS30  = GND
  CA6_A  = M_F_CPU1_SA_CA<6>
  VSS31  = GND
  PAR_A  = M_F_CPU1_SA_PAR
  VSS32  = GND
  CA0_B  = M_F_CPU1_SB_CA<0>
  VSS33  = GND
  CA2_B  = M_F_CPU1_SB_CA<2>
  VSS34  = GND
  CA4_B  = M_F_CPU1_SB_CA<4>
  VSS35  = GND
  CA6_B  = M_F_CPU1_SB_CA<6>
  VSS36  = GND
  CS0_B_N  = M_F_CPU1_SB_CS_N<0>
  VSS37  = GND
  \lbd||rsp_a_n\  = M_F_CPU1_SA_RSP<0>
  \lbs||rsp_b_n\  = M_F_CPU1_SB_RSP<0>
  VSS38  = GND
  CB4_B  = M_F_CPU1_SB_CB<4>
  VSS39  = GND
  CB5_B  = M_F_CPU1_SB_CB<5>
  VSS40  = GND
  \dqs9_b_t||tdqs9_b_t||dbi4_b_n\  = M_F_CPU1_SB_DQS_DP<9>
  \dqs9_b_c||tdqs9_b_c\  = M_F_CPU1_SB_DQS_DN<9>
  VSS41  = GND
  CB0_B  = M_F_CPU1_SB_CB<0>
  VSS42  = GND
  CB1_B  = M_F_CPU1_SB_CB<1>
  VSS43  = GND
  DQ0_B  = M_F_CPU1_SB_DQ<0>
  VSS44  = GND
  DQ1_B  = M_F_CPU1_SB_DQ<1>
  VSS45  = GND
  DQS0_B_T  = M_F_CPU1_SB_DQS_DP<0>
  DQS0_B_C  = M_F_CPU1_SB_DQS_DN<0>
  VSS46  = GND
  DQ4_B  = M_F_CPU1_SB_DQ<4>
  VSS47  = GND
  DQ5_B  = M_F_CPU1_SB_DQ<5>
  VSS48  = GND
  DQ8_B  = M_F_CPU1_SB_DQ<8>
  VSS49  = GND
  DQ9_B  = M_F_CPU1_SB_DQ<9>
  VSS50  = GND
  DQS1_B_T  = M_F_CPU1_SB_DQS_DP<1>
  DQS1_B_C  = M_F_CPU1_SB_DQS_DN<1>
  VSS51  = GND
  DQ12_B  = M_F_CPU1_SB_DQ<12>
  VSS52  = GND
  DQ13_B  = M_F_CPU1_SB_DQ<13>
  VSS53  = GND
  DQ16_B  = M_F_CPU1_SB_DQ<16>
  VSS54  = GND
  DQ17_B  = M_F_CPU1_SB_DQ<17>
  VSS55  = GND
  DQS2_B_T  = M_F_CPU1_SB_DQS_DP<2>
  DQS2_B_C  = M_F_CPU1_SB_DQS_DN<2>
  VSS56  = GND
  DQ20_B  = M_F_CPU1_SB_DQ<20>
  VSS57  = GND
  DQ21_B  = M_F_CPU1_SB_DQ<21>
  VSS58  = GND
  DQ24_B  = M_F_CPU1_SB_DQ<24>
  VSS59  = GND
  DQ25_B  = M_F_CPU1_SB_DQ<25>
  VSS60  = GND
  DQS3_B_T  = M_F_CPU1_SB_DQS_DP<3>
  DQS3_B_C  = M_F_CPU1_SB_DQS_DN<3>
  VSS61  = GND
  DQ28_B  = M_F_CPU1_SB_DQ<28>
  VSS62  = GND
  DQ29_B  = M_F_CPU1_SB_DQ<29>
  VSS63  = GND
  RFU1  = TP_CHF_CPU1_DIMM1_FRU_1
  VIN_BULK1  = P12V_S3_AUX_CPU1_NVDIMM
  VIN_BULK2  = P12V_S3_AUX_CPU1_NVDIMM
  \pwr_good||fail_n\  = PWRGD_CHF_CPU1_DIMM1
  HSA  = PD_CHF_CPU1_DIMM1_SAA
  RFU2  = TP_CHF_CPU1_DIMM1_FRU_2
  RFU3  = TP_CHF_CPU1_DIMM1_FRU_3
  VSS64  = GND
  DQ2_A  = M_F_CPU1_SA_DQ<2>
  VSS65  = GND
  DQ3_A  = M_F_CPU1_SA_DQ<3>
  VSS66  = GND
  \dqs5_a_c||tdqs5_a_c||dqs5_a_t||tdqs5_a_t\  = M_F_CPU1_SA_DQS_DN<5>
  \dqs5_a_t||tdqs5_a_t\  = M_F_CPU1_SA_DQS_DP<5>
  VSS67  = GND
  DQ6_A  = M_F_CPU1_SA_DQ<6>
  VSS68  = GND
  DQ7_A  = M_F_CPU1_SA_DQ<7>
  VSS69  = GND
  DQ10_A  = M_F_CPU1_SA_DQ<10>
  VSS70  = GND
  DQ11_A  = M_F_CPU1_SA_DQ<11>
  VSS71  = GND
  \dqs6_a_c||tdqs6_a_c||dqs6_a_t||tdqs6_a_t\  = M_F_CPU1_SA_DQS_DN<6>
  \dqs6_a_t||tdqs6_a_t\  = M_F_CPU1_SA_DQS_DP<6>
  VSS72  = GND
  DQ14_A  = M_F_CPU1_SA_DQ<14>
  VSS73  = GND
  DQ15_A  = M_F_CPU1_SA_DQ<15>
  VSS74  = GND
  DQ18_A  = M_F_CPU1_SA_DQ<18>
  VSS75  = GND
  DQ19_A  = M_F_CPU1_SA_DQ<19>
  VSS76  = GND
  \dqs7_a_c||tdqs7_a_c\  = M_F_CPU1_SA_DQS_DN<7>
  \dqs7_a_t||tdqs7_a_t\  = M_F_CPU1_SA_DQS_DP<7>
  VSS77  = GND
  DQ22_A  = M_F_CPU1_SA_DQ<22>
  VSS78  = GND
  DQ23_A  = M_F_CPU1_SA_DQ<23>
  VSS79  = GND
  DQ26_A  = M_F_CPU1_SA_DQ<26>
  VSS80  = GND
  DQ27_A  = M_F_CPU1_SA_DQ<27>
  VSS81  = GND
  \dqs8_a_c||tdqs8_a_c\  = M_F_CPU1_SA_DQS_DN<8>
  \dqs8_a_t||tdqs8_a_t\  = M_F_CPU1_SA_DQS_DP<8>
  VSS82  = GND
  DQ30_A  = M_F_CPU1_SA_DQ<30>
  VSS83  = GND
  DQ31_A  = M_F_CPU1_SA_DQ<31>
  VSS84  = GND
  CB2_A  = M_F_CPU1_SA_CB<2>
  VSS85  = GND
  CB3_A  = M_F_CPU1_SA_CB<3>
  VSS86  = GND
  \dqs9_a_c||tdqs9_a_c\  = M_F_CPU1_SA_DQS_DN<9>
  \dqs9_a_t||tdqs9_a_t\  = M_F_CPU1_SA_DQS_DP<9>
  VSS87  = GND
  CB6_A  = M_F_CPU1_SA_CB<6>
  VSS88  = GND
  CB7_A  = M_F_CPU1_SA_CB<7>
  VSS89  = GND
  RESET_N  = RST_M_EF_CPU1_FPGA_N
  VSS90  = GND
  CS1_A_N  = M_F_CPU1_SA_CS_N<1>
  VSS91  = GND
  CA1_A  = M_F_CPU1_SA_CA<1>
  VSS92  = GND
  CA3_A  = M_F_CPU1_SA_CA<3>
  VSS93  = GND
  CA5_A  = M_F_CPU1_SA_CA<5>
  VSS94  = GND
  CK_T  = M_F_CPU1_CLK_DP<0>
  CK_C  = M_F_CPU1_CLK_DN<0>
  VSS95  = GND
  RFU4  = TP_CHF_CPU1_DIMM1_FRU_4
  CA1_B  = M_F_CPU1_SB_CA<1>
  VSS96  = GND
  CA3_B  = M_F_CPU1_SB_CA<3>
  VSS97  = GND
  CA5_B  = M_F_CPU1_SB_CA<5>
  VSS98  = GND
  PAR_B  = M_F_CPU1_SB_PAR
  VSS99  = GND
  CS1_B_N  = M_F_CPU1_SB_CS_N<1>
  VSS100  = GND
  RFU5  = TP_CHF_CPU1_DIMM1_FRU_5
  RFU6  = TP_CHF_CPU1_DIMM1_FRU_6
  VSS101  = GND
  CB6_B  = M_F_CPU1_SB_CB<6>
  VSS102  = GND
  CB7_B  = M_F_CPU1_SB_CB<7>
  VSS103  = GND
  DQS4_B_C  = M_F_CPU1_SB_DQS_DN<4>
  DQS4_B_T  = M_F_CPU1_SB_DQS_DP<4>
  VSS104  = GND
  CB2_B  = M_F_CPU1_SB_CB<2>
  VSS105  = GND
  CB3_B  = M_F_CPU1_SB_CB<3>
  VSS106  = GND
  DQ2_B  = M_F_CPU1_SB_DQ<2>
  VSS107  = GND
  DQ3_B  = M_F_CPU1_SB_DQ<3>
  VSS108  = GND
  \dqs5_b_c||tdqs5_b_c\  = M_F_CPU1_SB_DQS_DN<5>
  \dqs5_b_t||tdqs5_b_t\  = M_F_CPU1_SB_DQS_DP<5>
  VSS109  = GND
  DQ6_B  = M_F_CPU1_SB_DQ<6>
  VSS110  = GND
  DQ7_B  = M_F_CPU1_SB_DQ<7>
  VSS111  = GND
  DQ10_B  = M_F_CPU1_SB_DQ<10>
  VSS112  = GND
  DQ11_B  = M_F_CPU1_SB_DQ<11>
  VSS113  = GND
  \dqs6_b_c||tdqs6_b_c\  = M_F_CPU1_SB_DQS_DN<6>
  \dqs6_b_t||tdqs6_b_t\  = M_F_CPU1_SB_DQS_DP<6>
  VSS114  = GND
  DQ14_B  = M_F_CPU1_SB_DQ<14>
  VSS115  = GND
  DQ15_B  = M_F_CPU1_SB_DQ<15>
  VSS116  = GND
  DQ18_B  = M_F_CPU1_SB_DQ<18>
  VSS117  = GND
  DQ19_B  = M_F_CPU1_SB_DQ<19>
  VSS118  = GND
  \dqs7_b_c||tdqs7_b_c\  = M_F_CPU1_SB_DQS_DN<7>
  \dqs7_b_t||tdqs7_b_t\  = M_F_CPU1_SB_DQS_DP<7>
  VSS119  = GND
  DQ22_B  = M_F_CPU1_SB_DQ<22>
  VSS120  = GND
  DQ23_B  = M_F_CPU1_SB_DQ<23>
  VSS121  = GND
  DQ26_B  = M_F_CPU1_SB_DQ<26>
  VSS122  = GND
  DQ27_B  = M_F_CPU1_SB_DQ<27>
  VSS123  = GND
  \dqs8_b_c||tdqs8_b_c\  = M_F_CPU1_SB_DQS_DN<8>
  \dqs8_b_t||tdqs8_b_t\  = M_F_CPU1_SB_DQS_DP<8>
  VSS124  = GND
  DQ30_B  = M_F_CPU1_SB_DQ<30>
  VSS125  = GND
  DQ31_B  = M_F_CPU1_SB_DQ<31>
  VSS126  = GND
  G1  = GND
  G2  = GND
  G3  = GND

(kicad_pcb
	(version 20260206)
	(generator "pcbnew")
	(generator_version "10.0")
	(general
		(thickness 1.6)
		(legacy_teardrops no)
	)
	(paper "A4")
	(title_block
		(title "03242023_DA0F0TMBIJ0_F0T_Motherboard_J_brd_V01_OCP.brd")
		(comment 1 "Grand Teton / footprint 1301 of 6105 (J27), pads 229-274 of 291")
	)
	(layers
		(0 "F.Cu" signal "TOP")
		(4 "In1.Cu" signal "GND")
		(6 "In2.Cu" signal "IN1")
		(8 "In3.Cu" signal "GND1")
		(10 "In4.Cu" signal "IN2")
		(12 "In5.Cu" signal "GND2")
		(14 "In6.Cu" signal "IN3")
		(16 "In7.Cu" signal "GND3")
		(18 "In8.Cu" signal "VCC")
		(20 "In9.Cu" signal "VCC1")
		(22 "In10.Cu" signal "GND4")
		(24 "In11.Cu" signal "IN4")
		(26 "In12.Cu" signal "GND5")
		(28 "In13.Cu" signal "IN5")
		(30 "In14.Cu" signal "GND6")
		(32 "In15.Cu" signal "IN6")
		(34 "In16.Cu" signal "GND7")
		(2 "B.Cu" signal "BOTTOM")
		(9 "F.Adhes" user "F.Adhesive")
		(11 "B.Adhes" user "B.Adhesive")
		(13 "F.Paste" user "Package Geometry/Pastemask Top")
		(15 "B.Paste" user "Package Geometry/Pastemask Bottom")
		(5 "F.SilkS" user "Ref Des/Silkscreen Top")
		(7 "B.SilkS" user "Ref Des/Silkscreen Bottom")
		(1 "F.Mask" user "Board Geometry/Soldermask Top")
		(3 "B.Mask" user "Board Geometry/Soldermask Bottom")
		(17 "Dwgs.User" user "User.Drawings")
		(19 "Cmts.User" user "User.Comments")
		(21 "Eco1.User" user "User.Eco1")
		(23 "Eco2.User" user "User.Eco2")
		(25 "Edge.Cuts" user "Board Geometry/Outline")
		(27 "Margin" user)
		(31 "F.CrtYd" user "Package Geometry/Place Bound Top")
		(29 "B.CrtYd" user "Package Geometry/Place Bound Bottom")
		(35 "F.Fab" user "Ref Des/Assembly Top")
		(33 "B.Fab" user "Ref Des/Assembly Bottom")
	)
	(footprint ""
		(layer "F.Cu")
		(at 183.49468 -258.091686)
		(property "Reference" "J27"
			(at 2.19456 -81.755488 0)
			(unlocked yes)
			(layer "F.SilkS")
			(effects
				(font
					(size 0.7874 0.5842)
					(thickness 0.1524)
				)
				(justify left)
			)
		)
		(property "Value" ""
			(at 0 0 0)
			(layer "F.Fab")
			(effects
				(font
					(size 1.27 1.27)
				)
			)
		)
		(duplicate_pad_numbers_are_jumpers no)
		(pad "229" smd rect
			(at 2.050034 13.17498 270)
			(size 0.519938 1.4986)
			(layers "F.Cu" "F.Mask" "F.Paste")
			(net "M_F_CPU1_SB_CS_N<1>")
		)
		(pad "230" smd rect
			(at 2.050034 14.025118 270)
			(size 0.519938 1.4986)
			(layers "F.Cu" "F.Mask" "F.Paste")
			(net "GND")
		)
		(pad "231" smd rect
			(at 2.050034 14.875002 270)
			(size 0.519938 1.4986)
			(layers "F.Cu" "F.Mask" "F.Paste")
			(net "TP_CHF_CPU1_DIMM1_FRU_5")
		)
		(pad "232" smd rect
			(at 2.050034 15.724886 270)
			(size 0.519938 1.4986)
			(layers "F.Cu" "F.Mask" "F.Paste")
			(net "TP_CHF_CPU1_DIMM1_FRU_6")
		)
		(pad "233" smd rect
			(at 2.050034 16.575024 270)
			(size 0.519938 1.4986)
			(layers "F.Cu" "F.Mask" "F.Paste")
			(net "GND")
		)
		(pad "234" smd rect
			(at 2.050034 17.424908 270)
			(size 0.519938 1.4986)
			(layers "F.Cu" "F.Mask" "F.Paste")
			(net "M_F_CPU1_SB_CB<6>")
		)
		(pad "235" smd rect
			(at 2.050034 18.275046 270)
			(size 0.519938 1.4986)
			(layers "F.Cu" "F.Mask" "F.Paste")
			(net "GND")
		)
		(pad "236" smd rect
			(at 2.050034 19.12493 270)
			(size 0.519938 1.4986)
			(layers "F.Cu" "F.Mask" "F.Paste")
			(net "M_F_CPU1_SB_CB<7>")
		)
		(pad "237" smd rect
			(at 2.050034 19.975068 270)
			(size 0.519938 1.4986)
			(layers "F.Cu" "F.Mask" "F.Paste")
			(net "GND")
		)
		(pad "238" smd rect
			(at 2.050034 20.824952 270)
			(size 0.519938 1.4986)
			(layers "F.Cu" "F.Mask" "F.Paste")
			(net "M_F_CPU1_SB_DQS_DN<4>")
		)
		(pad "239" smd rect
			(at 2.050034 21.67509 270)
			(size 0.519938 1.4986)
			(layers "F.Cu" "F.Mask" "F.Paste")
			(net "M_F_CPU1_SB_DQS_DP<4>")
		)
		(pad "240" smd rect
			(at 2.050034 22.524974 270)
			(size 0.519938 1.4986)
			(layers "F.Cu" "F.Mask" "F.Paste")
			(net "GND")
		)
		(pad "241" smd rect
			(at 2.050034 23.375112 270)
			(size 0.519938 1.4986)
			(layers "F.Cu" "F.Mask" "F.Paste")
			(net "M_F_CPU1_SB_CB<2>")
		)
		(pad "242" smd rect
			(at 2.050034 24.224996 270)
			(size 0.519938 1.4986)
			(layers "F.Cu" "F.Mask" "F.Paste")
			(net "GND")
		)
		(pad "243" smd rect
			(at 2.050034 25.07488 270)
			(size 0.519938 1.4986)
			(layers "F.Cu" "F.Mask" "F.Paste")
			(net "M_F_CPU1_SB_CB<3>")
		)
		(pad "244" smd rect
			(at 2.050034 25.925018 270)
			(size 0.519938 1.4986)
			(layers "F.Cu" "F.Mask" "F.Paste")
			(net "GND")
		)
		(pad "245" smd rect
			(at 2.050034 26.774902 270)
			(size 0.519938 1.4986)
			(layers "F.Cu" "F.Mask" "F.Paste")
			(net "M_F_CPU1_SB_DQ<2>")
		)
		(pad "246" smd rect
			(at 2.050034 27.62504 270)
			(size 0.519938 1.4986)
			(layers "F.Cu" "F.Mask" "F.Paste")
			(net "GND")
		)
		(pad "247" smd rect
			(at 2.050034 28.474924 270)
			(size 0.519938 1.4986)
			(layers "F.Cu" "F.Mask" "F.Paste")
			(net "M_F_CPU1_SB_DQ<3>")
		)
		(pad "248" smd rect
			(at 2.050034 29.325062 270)
			(size 0.519938 1.4986)
			(layers "F.Cu" "F.Mask" "F.Paste")
			(net "GND")
		)
		(pad "249" smd rect
			(at 2.050034 30.174946 270)
			(size 0.519938 1.4986)
			(layers "F.Cu" "F.Mask" "F.Paste")
			(net "M_F_CPU1_SB_DQS_DN<5>")
		)
		(pad "250" smd rect
			(at 2.050034 31.025084 270)
			(size 0.519938 1.4986)
			(layers "F.Cu" "F.Mask" "F.Paste")
			(net "M_F_CPU1_SB_DQS_DP<5>")
		)
		(pad "251" smd rect
			(at 2.050034 31.874968 270)
			(size 0.519938 1.4986)
			(layers "F.Cu" "F.Mask" "F.Paste")
			(net "GND")
		)
		(pad "252" smd rect
			(at 2.050034 32.725106 270)
			(size 0.519938 1.4986)
			(layers "F.Cu" "F.Mask" "F.Paste")
			(net "M_F_CPU1_SB_DQ<6>")
		)
		(pad "253" smd rect
			(at 2.050034 33.57499 270)
			(size 0.519938 1.4986)
			(layers "F.Cu" "F.Mask" "F.Paste")
			(net "GND")
		)
		(pad "254" smd rect
			(at 2.050034 34.425128 270)
			(size 0.519938 1.4986)
			(layers "F.Cu" "F.Mask" "F.Paste")
			(net "M_F_CPU1_SB_DQ<7>")
		)
		(pad "255" smd rect
			(at 2.050034 35.275012 270)
			(size 0.519938 1.4986)
			(layers "F.Cu" "F.Mask" "F.Paste")
			(net "GND")
		)
		(pad "256" smd rect
			(at 2.050034 36.124896 270)
			(size 0.519938 1.4986)
			(layers "F.Cu" "F.Mask" "F.Paste")
			(net "M_F_CPU1_SB_DQ<10>")
		)
		(pad "257" smd rect
			(at 2.050034 36.975034 270)
			(size 0.519938 1.4986)
			(layers "F.Cu" "F.Mask" "F.Paste")
			(net "GND")
		)
		(pad "258" smd rect
			(at 2.050034 37.824918 270)
			(size 0.519938 1.4986)
			(layers "F.Cu" "F.Mask" "F.Paste")
			(net "M_F_CPU1_SB_DQ<11>")
		)
		(pad "259" smd rect
			(at 2.050034 38.675056 270)
			(size 0.519938 1.4986)
			(layers "F.Cu" "F.Mask" "F.Paste")
			(net "GND")
		)
		(pad "260" smd rect
			(at 2.050034 39.52494 270)
			(size 0.519938 1.4986)
			(layers "F.Cu" "F.Mask" "F.Paste")
			(net "M_F_CPU1_SB_DQS_DN<6>")
		)
		(pad "261" smd rect
			(at 2.050034 40.375078 270)
			(size 0.519938 1.4986)
			(layers "F.Cu" "F.Mask" "F.Paste")
			(net "M_F_CPU1_SB_DQS_DP<6>")
		)
		(pad "262" smd rect
			(at 2.050034 41.224962 270)
			(size 0.519938 1.4986)
			(layers "F.Cu" "F.Mask" "F.Paste")
			(net "GND")
		)
		(pad "263" smd rect
			(at 2.050034 42.0751 270)
			(size 0.519938 1.4986)
			(layers "F.Cu" "F.Mask" "F.Paste")
			(net "M_F_CPU1_SB_DQ<14>")
		)
		(pad "264" smd rect
			(at 2.050034 42.924984 270)
			(size 0.519938 1.4986)
			(layers "F.Cu" "F.Mask" "F.Paste")
			(net "GND")
		)
		(pad "265" smd rect
			(at 2.050034 43.775122 270)
			(size 0.519938 1.4986)
			(layers "F.Cu" "F.Mask" "F.Paste")
			(net "M_F_CPU1_SB_DQ<15>")
		)
		(pad "266" smd rect
			(at 2.050034 44.625006 270)
			(size 0.519938 1.4986)
			(layers "F.Cu" "F.Mask" "F.Paste")
			(net "GND")
		)
		(pad "267" smd rect
			(at 2.050034 45.47489 270)
			(size 0.519938 1.4986)
			(layers "F.Cu" "F.Mask" "F.Paste")
			(net "M_F_CPU1_SB_DQ<18>")
		)
		(pad "268" smd rect
			(at 2.050034 46.325028 270)
			(size 0.519938 1.4986)
			(layers "F.Cu" "F.Mask" "F.Paste")
			(net "GND")
		)
		(pad "269" smd rect
			(at 2.050034 47.174912 270)
			(size 0.519938 1.4986)
			(layers "F.Cu" "F.Mask" "F.Paste")
			(net "M_F_CPU1_SB_DQ<19>")
		)
		(pad "270" smd rect
			(at 2.050034 48.02505 270)
			(size 0.519938 1.4986)
			(layers "F.Cu" "F.Mask" "F.Paste")
			(net "GND")
		)
		(pad "271" smd rect
			(at 2.050034 48.874934 270)
			(size 0.519938 1.4986)
			(layers "F.Cu" "F.Mask" "F.Paste")
			(net "M_F_CPU1_SB_DQS_DN<7>")
		)
		(pad "272" smd rect
			(at 2.050034 49.725072 270)
			(size 0.519938 1.4986)
			(layers "F.Cu" "F.Mask" "F.Paste")
			(net "M_F_CPU1_SB_DQS_DP<7>")
		)
		(pad "273" smd rect
			(at 2.050034 50.574956 270)
			(size 0.519938 1.4986)
			(layers "F.Cu" "F.Mask" "F.Paste")
			(net "GND")
		)
		(pad "274" smd rect
			(at 2.050034 51.425094 270)
			(size 0.519938 1.4986)
			(layers "F.Cu" "F.Mask" "F.Paste")
			(net "M_F_CPU1_SB_DQ<22>")
		)
	)
)
